(kicad_sch
	(version 20250114)
	(generator "eeschema")
	(generator_version "9.0")
	(paper "A3")
	(title_block
		(title "OCuLink to PCIe adapter")
		(date "2025-06-18")
		(rev "1.0.0")
		(company "Antmicro Ltd")
		(comment 1 "www.antmicro.com")
	)
	(text "Ideal diode"
		(exclude_from_sim no)
		(at 197.866 129.794 0)
		(effects
			(font
				(size 2 2)
				(thickness 0.4)
				(bold yes)
			)
			(justify left bottom)
		)
	)
	(junction
		(at 194.31 162.56)
		(diameter 0)
		(color 0 0 0 0)
	)
	(junction
		(at 194.31 157.48)
		(diameter 0)
		(color 0 0 0 0)
	)
	(junction
		(at 223.52 139.7)
		(diameter 0)
		(color 0 0 0 0)
	)
	(junction
		(at 185.42 152.4)
		(diameter 0)
		(color 0 0 0 0)
	)
	(junction
		(at 185.42 139.7)
		(diameter 0)
		(color 0 0 0 0)
	)
	(junction
		(at 223.52 152.4)
		(diameter 0)
		(color 0 0 0 0)
	)
	(no_connect
		(at 214.63 157.48)
	)
	(wire
		(pts
			(xy 185.42 152.4) (xy 185.42 154.94)
		)
		(stroke
			(width 0)
			(type default)
		)
	)
	(wire
		(pts
			(xy 194.31 154.94) (xy 196.85 154.94)
		)
		(stroke
			(width 0)
			(type default)
		)
	)
	(wire
		(pts
			(xy 194.31 157.48) (xy 194.31 162.56)
		)
		(stroke
			(width 0)
			(type default)
		)
	)
	(wire
		(pts
			(xy 194.31 154.94) (xy 194.31 157.48)
		)
		(stroke
			(width 0)
			(type default)
		)
	)
	(wire
		(pts
			(xy 217.17 146.05) (xy 217.17 154.94)
		)
		(stroke
			(width 0)
			(type default)
		)
	)
	(wire
		(pts
			(xy 194.31 157.48) (xy 196.85 157.48)
		)
		(stroke
			(width 0)
			(type default)
		)
	)
	(wire
		(pts
			(xy 194.31 162.56) (xy 194.31 165.1)
		)
		(stroke
			(width 0)
			(type default)
		)
	)
	(wire
		(pts
			(xy 185.42 152.4) (xy 196.85 152.4)
		)
		(stroke
			(width 0)
			(type default)
		)
	)
	(wire
		(pts
			(xy 223.52 160.02) (xy 223.52 165.1)
		)
		(stroke
			(width 0)
			(type default)
		)
	)
	(wire
		(pts
			(xy 219.71 139.7) (xy 223.52 139.7)
		)
		(stroke
			(width 0)
			(type default)
		)
	)
	(wire
		(pts
			(xy 214.63 154.94) (xy 217.17 154.94)
		)
		(stroke
			(width 0)
			(type default)
		)
	)
	(wire
		(pts
			(xy 223.52 139.7) (xy 223.52 152.4)
		)
		(stroke
			(width 0)
			(type default)
		)
	)
	(wire
		(pts
			(xy 223.52 139.7) (xy 226.06 139.7)
		)
		(stroke
			(width 0)
			(type default)
		)
	)
	(wire
		(pts
			(xy 185.42 162.56) (xy 194.31 162.56)
		)
		(stroke
			(width 0)
			(type default)
		)
	)
	(wire
		(pts
			(xy 185.42 160.02) (xy 185.42 162.56)
		)
		(stroke
			(width 0)
			(type default)
		)
	)
	(wire
		(pts
			(xy 214.63 152.4) (xy 223.52 152.4)
		)
		(stroke
			(width 0)
			(type default)
		)
	)
	(wire
		(pts
			(xy 185.42 139.7) (xy 185.42 152.4)
		)
		(stroke
			(width 0)
			(type default)
		)
	)
	(wire
		(pts
			(xy 182.88 139.7) (xy 185.42 139.7)
		)
		(stroke
			(width 0)
			(type default)
		)
	)
	(wire
		(pts
			(xy 223.52 152.4) (xy 223.52 154.94)
		)
		(stroke
			(width 0)
			(type default)
		)
	)
	(wire
		(pts
			(xy 185.42 139.7) (xy 209.55 139.7)
		)
		(stroke
			(width 0)
			(type default)
		)
	)
	(hierarchical_label "VIN"
		(shape input)
		(at 182.88 139.7 180)
		(effects
			(font
				(size 1.27 1.27)
			)
			(justify right)
		)
	)
	(hierarchical_label "VOUT"
		(shape output)
		(at 226.06 139.7 0)
		(effects
			(font
				(size 1.27 1.27)
			)
			(justify left)
		)
	)
	(symbol
		(lib_id "antmicroCapacitors0402:C_100n_0402")
		(at 185.42 160.02 90)
		(unit 1)
		(exclude_from_sim no)
		(in_bom yes)
		(on_board yes)
		(dnp no)
		(property "Reference" "C32"
			(at 187.198 156.21 90)
			(effects
				(font
					(size 1.27 1.27)
					(thickness 0.15)
				)
				(justify right)
			)
		)
		(property "Value" "C_100n_0402"
			(at 195.58 139.7 0)
			(effects
				(font
					(size 1.27 1.27)
					(thickness 0.15)
				)
				(justify left bottom)
				(hide yes)
			)
		)
		(property "Footprint" "antmicro-footprints:C_0402_1005Metric"
			(at 198.12 139.7 0)
			(effects
				(font
					(size 1.27 1.27)
					(thickness 0.15)
				)
				(justify left bottom)
				(hide yes)
			)
		)
		(property "Datasheet" "https://www.murata.com/products/productdetail?partno=GRM155R61H104KE14%23"
			(at 200.66 139.7 0)
			(effects
				(font
					(size 1.27 1.27)
					(thickness 0.15)
				)
				(justify left bottom)
				(hide yes)
			)
		)
		(property "Description" "SMD Multilayer Ceramic Capacitor, 0.1 µF, 50 V, 0402 [1005 Metric], ± 10%, X5R, GRM Series"
			(at 185.42 160.02 0)
			(effects
				(font
					(size 1.27 1.27)
				)
				(hide yes)
			)
		)
		(property "MPN" "GRM155R61H104KE14D"
			(at 203.2 139.7 0)
			(effects
				(font
					(size 1.27 1.27)
					(thickness 0.15)
				)
				(justify left bottom)
				(hide yes)
			)
		)
		(property "Manufacturer" "Murata"
			(at 205.74 139.7 0)
			(effects
				(font
					(size 1.27 1.27)
					(thickness 0.15)
				)
				(justify left bottom)
				(hide yes)
			)
		)
		(property "License" "Apache-2.0"
			(at 208.28 139.7 0)
			(effects
				(font
					(size 1.27 1.27)
					(thickness 0.15)
				)
				(justify left bottom)
				(hide yes)
			)
		)
		(property "Author" "Antmicro"
			(at 210.82 139.7 0)
			(effects
				(font
					(size 1.27 1.27)
					(thickness 0.15)
				)
				(justify left bottom)
				(hide yes)
			)
		)
		(property "Val" "100n"
			(at 187.198 158.75 90)
			(effects
				(font
					(size 1.27 1.27)
					(thickness 0.15)
				)
				(justify right)
			)
		)
		(property "Voltage" "50V"
			(at 213.36 139.7 0)
			(effects
				(font
					(size 1.27 1.27)
				)
				(justify left bottom)
				(hide yes)
			)
		)
		(property "Dielectric" "X5R"
			(at 215.9 139.7 0)
			(effects
				(font
					(size 1.27 1.27)
				)
				(justify left bottom)
				(hide yes)
			)
		)
		(pin "2"
		)
		(pin "1"
		)
		(instances
			(project "oculink-to-pcie-adapter"
				(path ""
					(reference "C34")
					(unit 1)
				)
				(path ""
					(reference "C32")
					(unit 1)
				)
				(path ""
					(reference "C13")
					(unit 1)
				)
			)
		)
	)
	(symbol
		(lib_id "antmicroPMICORControllersIdealDiodes:LTC4412IS6")
		(at 196.85 152.4 0)
		(unit 1)
		(exclude_from_sim no)
		(in_bom yes)
		(on_board yes)
		(dnp no)
		(property "Reference" "U3"
			(at 205.74 145.796 0)
			(effects
				(font
					(size 1.27 1.27)
					(thickness 0.15)
				)
			)
		)
		(property "Value" "LTC4412IS6"
			(at 228.6 157.48 0)
			(effects
				(font
					(size 1.27 1.27)
					(thickness 0.15)
				)
				(justify left bottom)
				(hide yes)
			)
		)
		(property "Footprint" "antmicro-footprints:SOT-23-6"
			(at 228.6 160.02 0)
			(effects
				(font
					(size 1.27 1.27)
					(thickness 0.15)
				)
				(justify left bottom)
				(hide yes)
			)
		)
		(property "Datasheet" "https://www.analog.com/media/en/technical-documentation/data-sheets/4412fb.pdf"
			(at 228.6 162.56 0)
			(effects
				(font
					(size 1.27 1.27)
					(thickness 0.15)
				)
				(justify left bottom)
				(hide yes)
			)
		)
		(property "Description" "Ideal diode controller"
			(at 196.85 152.4 0)
			(effects
				(font
					(size 1.27 1.27)
				)
				(hide yes)
			)
		)
		(property "MPN" "LTC4412IS6#TRMPBF"
			(at 205.74 148.336 0)
			(effects
				(font
					(size 1.27 1.27)
					(thickness 0.15)
				)
			)
		)
		(property "Manufacturer" "Analog Devices"
			(at 228.6 167.64 0)
			(effects
				(font
					(size 1.27 1.27)
					(thickness 0.15)
				)
				(justify left bottom)
				(hide yes)
			)
		)
		(property "Author" "Antmicro"
			(at 228.6 170.18 0)
			(effects
				(font
					(size 1.27 1.27)
					(thickness 0.15)
				)
				(justify left bottom)
				(hide yes)
			)
		)
		(property "License" "Apache-2.0"
			(at 228.6 172.72 0)
			(effects
				(font
					(size 1.27 1.27)
					(thickness 0.15)
				)
				(justify left bottom)
				(hide yes)
			)
		)
		(pin "6"
		)
		(pin "5"
		)
		(pin "4"
		)
		(pin "1"
		)
		(pin "3"
		)
		(pin "2"
		)
		(instances
			(project "oculink-to-pcie-adapter"
				(path ""
					(reference "U4")
					(unit 1)
				)
				(path ""
					(reference "U3")
					(unit 1)
				)
				(path ""
					(reference "U2")
					(unit 1)
				)
			)
		)
	)
	(symbol
		(lib_id "antmicropower:GND")
		(at 194.31 165.1 0)
		(unit 1)
		(exclude_from_sim no)
		(in_bom yes)
		(on_board yes)
		(dnp no)
		(fields_autoplaced yes)
		(property "Reference" "#PWR080"
			(at 194.31 171.45 0)
			(effects
				(font
					(size 1.27 1.27)
				)
				(hide yes)
			)
		)
		(property "Value" "GND"
			(at 192.405 169.545 0)
			(effects
				(font
					(size 1.27 1.27)
					(thickness 0.15)
				)
				(justify left bottom)
			)
		)
		(property "Footprint" ""
			(at 203.2 172.72 0)
			(effects
				(font
					(size 1.27 1.27)
					(thickness 0.15)
				)
				(justify left bottom)
				(hide yes)
			)
		)
		(property "Datasheet" ""
			(at 203.2 177.8 0)
			(effects
				(font
					(size 1.27 1.27)
					(thickness 0.15)
				)
				(justify left bottom)
				(hide yes)
			)
		)
		(property "Description" ""
			(at 194.31 165.1 0)
			(effects
				(font
					(size 1.27 1.27)
				)
			)
		)
		(property "Author" "Antmicro"
			(at 203.2 170.18 0)
			(effects
				(font
					(size 1.27 1.27)
					(thickness 0.15)
				)
				(justify left bottom)
				(hide yes)
			)
		)
		(property "License" "Apache-2.0"
			(at 203.2 172.72 0)
			(effects
				(font
					(size 1.27 1.27)
					(thickness 0.15)
				)
				(justify left bottom)
				(hide yes)
			)
		)
		(pin "1"
		)
		(instances
			(project "oculink-to-pcie-adapter"
				(path ""
					(reference "#PWR082")
					(unit 1)
				)
				(path ""
					(reference "#PWR080")
					(unit 1)
				)
				(path ""
					(reference "#PWR061")
					(unit 1)
				)
			)
		)
	)
	(symbol
		(lib_id "antmicroCapacitors0402:C_1u_25V_0402")
		(at 223.52 160.02 90)
		(unit 1)
		(exclude_from_sim no)
		(in_bom yes)
		(on_board yes)
		(dnp no)
		(property "Reference" "C33"
			(at 225.806 156.21 90)
			(effects
				(font
					(size 1.27 1.27)
					(thickness 0.15)
				)
				(justify right)
			)
		)
		(property "Value" "C_1u_25V_0402"
			(at 233.68 139.7 0)
			(effects
				(font
					(size 1.27 1.27)
					(thickness 0.15)
				)
				(justify left bottom)
				(hide yes)
			)
		)
		(property "Footprint" "antmicro-footprints:C_0402_1005Metric"
			(at 236.22 139.7 0)
			(effects
				(font
					(size 1.27 1.27)
					(thickness 0.15)
				)
				(justify left bottom)
				(hide yes)
			)
		)
		(property "Datasheet" "https://www.murata.com/products/productdetail?partno=GRM155R61E105KE11%23"
			(at 238.76 139.7 0)
			(effects
				(font
					(size 1.27 1.27)
					(thickness 0.15)
				)
				(justify left bottom)
				(hide yes)
			)
		)
		(property "Description" "SMD Multilayer Ceramic Capacitor, 1 µF, 25 V, 0402 [1005 Metric], ± 10%, X5R, GRM Series"
			(at 223.52 160.02 0)
			(effects
				(font
					(size 1.27 1.27)
				)
				(hide yes)
			)
		)
		(property "MPN" "GRM155R61E105KE11J"
			(at 241.3 139.7 0)
			(effects
				(font
					(size 1.27 1.27)
					(thickness 0.15)
				)
				(justify left bottom)
				(hide yes)
			)
		)
		(property "Manufacturer" "Murata"
			(at 243.84 139.7 0)
			(effects
				(font
					(size 1.27 1.27)
					(thickness 0.15)
				)
				(justify left bottom)
				(hide yes)
			)
		)
		(property "License" "Apache-2.0"
			(at 246.38 139.7 0)
			(effects
				(font
					(size 1.27 1.27)
					(thickness 0.15)
				)
				(justify left bottom)
				(hide yes)
			)
		)
		(property "Author" "Antmicro"
			(at 248.92 139.7 0)
			(effects
				(font
					(size 1.27 1.27)
					(thickness 0.15)
				)
				(justify left bottom)
				(hide yes)
			)
		)
		(property "Val" "1u"
			(at 225.806 158.75 90)
			(effects
				(font
					(size 1.27 1.27)
					(thickness 0.15)
				)
				(justify right)
			)
		)
		(property "Voltage" "25V"
			(at 251.46 139.7 0)
			(effects
				(font
					(size 1.27 1.27)
				)
				(justify left bottom)
				(hide yes)
			)
		)
		(property "Dielectric" "X5R"
			(at 254 139.7 0)
			(effects
				(font
					(size 1.27 1.27)
				)
				(justify left bottom)
				(hide yes)
			)
		)
		(pin "2"
		)
		(pin "1"
		)
		(instances
			(project "oculink-to-pcie-adapter"
				(path ""
					(reference "C35")
					(unit 1)
				)
				(path ""
					(reference "C33")
					(unit 1)
				)
				(path ""
					(reference "C14")
					(unit 1)
				)
			)
		)
	)
	(symbol
		(lib_id "antmicroTransistorsFETsMOSFETsSingle:SQS401EN-T1_BE3")
		(at 217.17 146.05 90)
		(unit 1)
		(exclude_from_sim no)
		(in_bom yes)
		(on_board yes)
		(dnp no)
		(property "Reference" "Q5"
			(at 214.63 133.35 90)
			(effects
				(font
					(size 1.27 1.27)
					(thickness 0.15)
				)
			)
		)
		(property "Value" "SQS401EN-T1_BE3"
			(at 227.33 130.81 0)
			(effects
				(font
					(size 1.27 1.27)
					(thickness 0.15)
				)
				(justify left bottom)
				(hide yes)
			)
		)
		(property "Footprint" "antmicro-footprints:Vishay_PowerPAK_1212-8_Single"
			(at 229.87 130.81 0)
			(effects
				(font
					(size 1.27 1.27)
					(thickness 0.15)
				)
				(justify left bottom)
				(hide yes)
			)
		)
		(property "Datasheet" "https://www.vishay.com/docs/65529/sqs401en.pdf"
			(at 232.41 130.81 0)
			(effects
				(font
					(size 1.27 1.27)
					(thickness 0.15)
				)
				(justify left bottom)
				(hide yes)
			)
		)
		(property "Description" "MOSFET, P Channel, 40 V, 16A, 0.047 ohm, PowerPAK 1212-8, Surface Mount"
			(at 217.17 146.05 0)
			(effects
				(font
					(size 1.27 1.27)
				)
				(hide yes)
			)
		)
		(property "MPN" "SQS401EN-T1_BE3"
			(at 214.63 135.89 90)
			(effects
				(font
					(size 1.27 1.27)
					(thickness 0.15)
				)
			)
		)
		(property "Manufacturer" "Vishay"
			(at 234.95 130.81 0)
			(effects
				(font
					(size 1.27 1.27)
					(thickness 0.15)
				)
				(justify left bottom)
				(hide yes)
			)
		)
		(property "Author" "Antmicro"
			(at 237.49 130.81 0)
			(effects
				(font
					(size 1.27 1.27)
					(thickness 0.15)
				)
				(justify left bottom)
				(hide yes)
			)
		)
		(property "License" "Apache-2.0"
			(at 240.03 130.81 0)
			(effects
				(font
					(size 1.27 1.27)
					(thickness 0.15)
				)
				(justify left bottom)
				(hide yes)
			)
		)
		(pin "4"
		)
		(pin "1"
		)
		(pin "3"
		)
		(pin "5"
		)
		(pin "2"
		)
		(instances
			(project "oculink-to-pcie-adapter"
				(path ""
					(reference "Q1")
					(unit 1)
				)
				(path ""
					(reference "Q5")
					(unit 1)
				)
				(path ""
					(reference "Q7")
					(unit 1)
				)
			)
		)
	)
	(symbol
		(lib_id "antmicropower:GND")
		(at 223.52 165.1 0)
		(unit 1)
		(exclude_from_sim no)
		(in_bom yes)
		(on_board yes)
		(dnp no)
		(fields_autoplaced yes)
		(property "Reference" "#PWR081"
			(at 223.52 171.45 0)
			(effects
				(font
					(size 1.27 1.27)
				)
				(hide yes)
			)
		)
		(property "Value" "GND"
			(at 221.615 169.545 0)
			(effects
				(font
					(size 1.27 1.27)
					(thickness 0.15)
				)
				(justify left bottom)
			)
		)
		(property "Footprint" ""
			(at 232.41 172.72 0)
			(effects
				(font
					(size 1.27 1.27)
					(thickness 0.15)
				)
				(justify left bottom)
				(hide yes)
			)
		)
		(property "Datasheet" ""
			(at 232.41 177.8 0)
			(effects
				(font
					(size 1.27 1.27)
					(thickness 0.15)
				)
				(justify left bottom)
				(hide yes)
			)
		)
		(property "Description" ""
			(at 223.52 165.1 0)
			(effects
				(font
					(size 1.27 1.27)
				)
			)
		)
		(property "Author" "Antmicro"
			(at 232.41 170.18 0)
			(effects
				(font
					(size 1.27 1.27)
					(thickness 0.15)
				)
				(justify left bottom)
				(hide yes)
			)
		)
		(property "License" "Apache-2.0"
			(at 232.41 172.72 0)
			(effects
				(font
					(size 1.27 1.27)
					(thickness 0.15)
				)
				(justify left bottom)
				(hide yes)
			)
		)
		(pin "1"
		)
		(instances
			(project "oculink-to-pcie-adapter"
				(path ""
					(reference "#PWR084")
					(unit 1)
				)
				(path ""
					(reference "#PWR081")
					(unit 1)
				)
				(path ""
					(reference "#PWR062")
					(unit 1)
				)
			)
		)
	)
)
